(kicad_pcb
	(version 20240108)
	(generator "pcbnew")
	(generator_version "8.0")
	(general
		(thickness 1.62)
		(legacy_teardrops no)
	)
	(paper "A4")
	(title_block
		(title "Jetson Orin Baseboard")
		(date "2025-03-12")
		(rev "1.3.4")
		(company "Antmicro Ltd")
		(comment 1 "www.antmicro.com")
		(comment 9 "footprints 125-128 of 677")
	)
	(layers
		(0 "F.Cu" signal)
		(1 "In1.Cu" signal)
		(2 "In2.Cu" signal)
		(3 "In3.Cu" signal)
		(4 "In4.Cu" jumper)
		(5 "In5.Cu" signal)
		(6 "In6.Cu" signal)
		(31 "B.Cu" signal)
		(32 "B.Adhes" user "B.Adhesive")
		(33 "F.Adhes" user "F.Adhesive")
		(34 "B.Paste" user)
		(35 "F.Paste" user)
		(36 "B.SilkS" user "B.Silkscreen")
		(37 "F.SilkS" user "F.Silkscreen")
		(38 "B.Mask" user)
		(39 "F.Mask" user)
		(40 "Dwgs.User" user "User.Drawings")
		(41 "Cmts.User" user "User.Comments")
		(42 "Eco1.User" user "User.Eco1")
		(43 "Eco2.User" user "User.Eco2")
		(44 "Edge.Cuts" user)
		(45 "Margin" user)
		(46 "B.CrtYd" user "B.Courtyard")
		(47 "F.CrtYd" user "F.Courtyard")
		(48 "B.Fab" user)
		(49 "F.Fab" user)
	)
	(footprint "antmicro-footprints:R_0402_1005Metric"
		(layer "F.Cu")
		(at 91.02 103.28 -135)
		(descr "Resistor SMD 0402")
		(tags "resistor SMD 0402")
		(property "Reference" "R220"
			(at 0.806102 0.636396 -135)
			(layer "F.SilkS")
			(effects
				(font
					(size 0.7 0.7)
					(thickness 0.15)
				)
				(justify left bottom)
			)
		)
		(property "Value" "R_499R_0402"
			(at -1.011843 1.772046 -135)
			(layer "F.Fab")
			(effects
				(font
					(size 0.7 0.7)
					(thickness 0.15)
				)
				(justify left bottom)
			)
		)
		(property "Footprint" "antmicro-footprints:R_0402_1005Metric"
			(at 0 0 -135)
			(layer "F.Fab")
			(hide yes)
			(effects
				(font
					(size 1.27 1.27)
					(thickness 0.15)
				)
			)
		)
		(property "Datasheet" "https://www.mouser.com/datasheet/2/54/cr-1858361.pdf"
			(at 0 0 -135)
			(layer "F.Fab")
			(hide yes)
			(effects
				(font
					(size 1.27 1.27)
					(thickness 0.15)
				)
			)
		)
		(property "Author" "Antmicro"
			(at 82.350871 240.670848 0)
			(layer "F.Fab")
			(hide yes)
			(effects
				(font
					(size 1 1)
					(thickness 0.15)
				)
			)
		)
		(property "License" "Apache-2.0"
			(at 82.350871 240.670848 0)
			(layer "F.Fab")
			(hide yes)
			(effects
				(font
					(size 1 1)
					(thickness 0.15)
				)
			)
		)
		(property "MPN" "CR0402-FX-4990GLF"
			(at 82.350871 240.670848 0)
			(layer "F.Fab")
			(hide yes)
			(effects
				(font
					(size 1 1)
					(thickness 0.15)
				)
			)
		)
		(property "Manufacturer" "Bourns"
			(at 82.350871 240.670848 0)
			(layer "F.Fab")
			(hide yes)
			(effects
				(font
					(size 1 1)
					(thickness 0.15)
				)
			)
		)
		(property "Tolerance" "1%"
			(at 82.350871 240.670848 0)
			(layer "F.Fab")
			(hide yes)
			(effects
				(font
					(size 1 1)
					(thickness 0.15)
				)
			)
		)
		(property "Val" "499R"
			(at 82.350871 240.670848 0)
			(layer "F.Fab")
			(hide yes)
			(effects
				(font
					(size 1 1)
					(thickness 0.15)
				)
			)
		)
		(sheetname "HDMI")
		(sheetfile "hdmi.kicad_sch")
		(attr smd)
		(fp_poly
			(pts
				(xy -0.925 -0.47) (xy 0.925 -0.47) (xy 0.925 0.47) (xy -0.925 0.47)
			)
			(stroke
				(width 0.05)
				(type default)
			)
			(fill none)
			(layer "F.CrtYd")
		)
		(fp_poly
			(pts
				(xy -0.5 -0.25) (xy 0.5 -0.25) (xy 0.5 0.25) (xy -0.5 0.25)
			)
			(stroke
				(width 0.15)
				(type solid)
			)
			(fill none)
			(layer "F.Fab")
		)
		(fp_text user "${REFERENCE}"
			(at -0.95 3.168 -135)
			(layer "F.Fab")
			(hide yes)
			(effects
				(font
					(size 0.7 0.7)
					(thickness 0.15)
				)
				(justify left bottom)
			)
		)
		(fp_text user "Author: Antmicro"
			(at -0.95 4.169 -135)
			(layer "F.Fab")
			(hide yes)
			(effects
				(font
					(size 0.7 0.7)
					(thickness 0.15)
				)
				(justify left bottom)
			)
		)
		(fp_text user "License: Apache-2.0"
			(at -0.949999 5.169 -135)
			(layer "F.Fab")
			(hide yes)
			(effects
				(font
					(size 0.7 0.7)
					(thickness 0.15)
				)
				(justify left bottom)
			)
		)
		(pad "1" smd roundrect
			(at -0.48 0 225)
			(size 0.59 0.64)
			(layers "F.Cu" "F.Paste" "F.Mask")
			(roundrect_rratio 0.25)
			(net 623 "Net-(Q2-D)")
			(pintype "passive")
		)
		(pad "2" smd roundrect
			(at 0.48 0 225)
			(size 0.59 0.64)
			(layers "F.Cu" "F.Paste" "F.Mask")
			(roundrect_rratio 0.25)
			(net 494 "/HDMI/HDMI_D0_P")
			(pintype "passive")
		)
	)
	(footprint "antmicro-footprints:R_0402_1005Metric"
		(layer "F.Cu")
		(at 108.175 110.625 90)
		(descr "Resistor SMD 0402")
		(tags "resistor SMD 0402")
		(property "Reference" "R118"
			(at -3.625 0.475 90)
			(layer "F.SilkS")
			(effects
				(font
					(size 0.7 0.7)
					(thickness 0.15)
				)
				(justify left bottom)
			)
		)
		(property "Value" "R_0R_0402"
			(at 0 1.4 90)
			(layer "F.Fab")
			(effects
				(font
					(size 0.7 0.7)
					(thickness 0.15)
				)
				(justify left bottom)
			)
		)
		(property "Footprint" "antmicro-footprints:R_0402_1005Metric"
			(at 0 0 90)
			(layer "F.Fab")
			(hide yes)
			(effects
				(font
					(size 1.27 1.27)
					(thickness 0.15)
				)
			)
		)
		(property "Datasheet" "https://industrial.panasonic.com/cdbs/www-data/pdf/RDA0000/AOA0000C301.pdf"
			(at 0 0 90)
			(layer "F.Fab")
			(hide yes)
			(effects
				(font
					(size 1.27 1.27)
					(thickness 0.15)
				)
			)
		)
		(property "Author" "Antmicro"
			(at 218.8 2.45 0)
			(layer "F.Fab")
			(hide yes)
			(effects
				(font
					(size 1 1)
					(thickness 0.15)
				)
			)
		)
		(property "Current" "1A"
			(at 218.8 2.45 0)
			(layer "F.Fab")
			(hide yes)
			(effects
				(font
					(size 1 1)
					(thickness 0.15)
				)
			)
		)
		(property "License" "Apache-2.0"
			(at 218.8 2.45 0)
			(layer "F.Fab")
			(hide yes)
			(effects
				(font
					(size 1 1)
					(thickness 0.15)
				)
			)
		)
		(property "MPN" "ERJ2GE0R00X"
			(at 218.8 2.45 0)
			(layer "F.Fab")
			(hide yes)
			(effects
				(font
					(size 1 1)
					(thickness 0.15)
				)
			)
		)
		(property "Manufacturer" "Panasonic"
			(at 218.8 2.45 0)
			(layer "F.Fab")
			(hide yes)
			(effects
				(font
					(size 1 1)
					(thickness 0.15)
				)
			)
		)
		(property "Tolerance" ""
			(at 218.8 2.45 0)
			(layer "F.Fab")
			(hide yes)
			(effects
				(font
					(size 1 1)
					(thickness 0.15)
				)
			)
		)
		(property "Val" "0R"
			(at 218.8 2.45 0)
			(layer "F.Fab")
			(hide yes)
			(effects
				(font
					(size 1 1)
					(thickness 0.15)
				)
			)
		)
		(sheetname "USB3")
		(sheetfile "usb3.kicad_sch")
		(attr smd)
		(fp_rect
			(start -0.925 -0.47)
			(end 0.925 0.47)
			(stroke
				(width 0.05)
				(type default)
			)
			(fill none)
			(layer "F.CrtYd")
		)
		(fp_rect
			(start -0.5 -0.25)
			(end 0.5 0.25)
			(stroke
				(width 0.15)
				(type solid)
			)
			(fill none)
			(layer "F.Fab")
		)
		(fp_text user "License: Apache-2.0"
			(at -0.95 5.169 90)
			(layer "F.Fab")
			(hide yes)
			(effects
				(font
					(size 0.7 0.7)
					(thickness 0.15)
				)
				(justify left bottom)
			)
		)
		(fp_text user "${REFERENCE}"
			(at -0.95 3.168 90)
			(layer "F.Fab")
			(hide yes)
			(effects
				(font
					(size 0.7 0.7)
					(thickness 0.15)
				)
				(justify left bottom)
			)
		)
		(fp_text user "Author: Antmicro"
			(at -0.95 4.169 90)
			(layer "F.Fab")
			(hide yes)
			(effects
				(font
					(size 0.7 0.7)
					(thickness 0.15)
				)
				(justify left bottom)
			)
		)
		(pad "1" smd roundrect
			(at -0.48 0 90)
			(size 0.59 0.64)
			(layers "F.Cu" "F.Paste" "F.Mask")
			(roundrect_rratio 0.25)
			(net 1 "GND")
			(pintype "passive")
		)
		(pad "2" smd roundrect
			(at 0.48 0 90)
			(size 0.59 0.64)
			(layers "F.Cu" "F.Paste" "F.Mask")
			(roundrect_rratio 0.25)
			(net 318 "/USB3/~{USBC1_EN_MUX}")
			(pintype "passive")
		)
	)
	(footprint "antmicro-footprints:C_0603_1608Metric_EIA"
		(layer "F.Cu")
		(at 58 94.63 90)
		(descr "Capacitor SMD 0603, IPC-7351 Density Level A")
		(tags "Capacitor 0603")
		(property "Reference" "C129"
			(at -2.32 28.186666 90)
			(layer "F.SilkS")
			(effects
				(font
					(size 0.7 0.7)
					(thickness 0.15)
				)
				(justify left bottom)
			)
		)
		(property "Value" "C_22u_16V_0603"
			(at -1.42757 1.770288 90)
			(layer "F.Fab")
			(effects
				(font
					(size 0.7 0.7)
					(thickness 0.15)
				)
				(justify left bottom)
			)
		)
		(property "Footprint" "antmicro-footprints:C_0603_1608Metric_EIA"
			(at 0 0 90)
			(layer "F.Fab")
			(hide yes)
			(effects
				(font
					(size 1.27 1.27)
					(thickness 0.15)
				)
			)
		)
		(property "Datasheet" "https://product.samsungsem.com/mlcc/CL10A226MO7JZN.do"
			(at 0 0 90)
			(layer "F.Fab")
			(hide yes)
			(effects
				(font
					(size 1.27 1.27)
					(thickness 0.15)
				)
			)
		)
		(property "Description" "SMD Multilayer Ceramic Capacitor"
			(at 0 0 90)
			(layer "F.Fab")
			(hide yes)
			(effects
				(font
					(size 1.27 1.27)
					(thickness 0.15)
				)
			)
		)
		(property "Manufacturer" "Samsung Electro-Mechanics"
			(at 0 0 90)
			(unlocked yes)
			(layer "F.Fab")
			(hide yes)
			(effects
				(font
					(size 1 1)
					(thickness 0.15)
				)
			)
		)
		(property "MPN" "CL10A226MO7JZNC"
			(at 0 0 90)
			(unlocked yes)
			(layer "F.Fab")
			(hide yes)
			(effects
				(font
					(size 1 1)
					(thickness 0.15)
				)
			)
		)
		(property "Val" "22u"
			(at 0 0 90)
			(unlocked yes)
			(layer "F.Fab")
			(hide yes)
			(effects
				(font
					(size 1 1)
					(thickness 0.15)
				)
			)
		)
		(property "License" "Apache-2.0"
			(at 0 0 90)
			(unlocked yes)
			(layer "F.Fab")
			(hide yes)
			(effects
				(font
					(size 1 1)
					(thickness 0.15)
				)
			)
		)
		(property "Author" "Antmicro"
			(at 0 0 90)
			(unlocked yes)
			(layer "F.Fab")
			(hide yes)
			(effects
				(font
					(size 1 1)
					(thickness 0.15)
				)
			)
		)
		(property "Voltage" "16V"
			(at 0 0 90)
			(unlocked yes)
			(layer "F.Fab")
			(hide yes)
			(effects
				(font
					(size 1 1)
					(thickness 0.15)
				)
			)
		)
		(property "Dielectric" ""
			(at 0 0 90)
			(unlocked yes)
			(layer "F.Fab")
			(hide yes)
			(effects
				(font
					(size 1 1)
					(thickness 0.15)
				)
			)
		)
		(sheetname "Supply")
		(sheetfile "supply.kicad_sch")
		(attr smd)
		(fp_line
			(start -0.15 -0.55)
			(end 0.15 -0.55)
			(stroke
				(width 0.15)
				(type solid)
			)
			(layer "F.SilkS")
		)
		(fp_line
			(start -0.15 0.55)
			(end 0.15 0.55)
			(stroke
				(width 0.15)
				(type solid)
			)
			(layer "F.SilkS")
		)
		(fp_rect
			(start -1.25 -0.65)
			(end 1.25 0.65)
			(stroke
				(width 0.05)
				(type solid)
			)
			(fill none)
			(layer "F.CrtYd")
		)
		(fp_rect
			(start -0.8 -0.45)
			(end 0.8 0.45)
			(stroke
				(width 0.15)
				(type solid)
			)
			(fill none)
			(layer "F.Fab")
		)
		(fp_text user "${REFERENCE}"
			(at -1.682 3.895 90)
			(layer "F.Fab")
			(hide yes)
			(effects
				(font
					(size 0.7 0.7)
					(thickness 0.15)
				)
				(justify left bottom)
			)
		)
		(fp_text user "License: Apache-2.0"
			(at -1.682 5.895 90)
			(layer "F.Fab")
			(hide yes)
			(effects
				(font
					(size 0.7 0.7)
					(thickness 0.15)
				)
				(justify left bottom)
			)
		)
		(fp_text user "Author: Antmicro"
			(at -1.682 4.894 90)
			(layer "F.Fab")
			(hide yes)
			(effects
				(font
					(size 0.7 0.7)
					(thickness 0.15)
				)
				(justify left bottom)
			)
		)
		(pad "1" smd roundrect
			(at -0.7 0 90)
			(size 0.8 1.1)
			(layers "F.Cu" "F.Paste" "F.Mask")
			(roundrect_rratio 0.2)
			(net 1 "GND")
			(pintype "passive")
		)
		(pad "2" smd roundrect
			(at 0.7 0 90)
			(size 0.8 1.1)
			(layers "F.Cu" "F.Paste" "F.Mask")
			(roundrect_rratio 0.2)
			(net 761 "/Supply/5V_OUT")
			(pintype "passive")
		)
	)
	(footprint "antmicro-footprints:USON-10_2.5x1mm_P0.5mm"
		(layer "F.Cu")
		(at 116.55 116.178749 90)
		(descr "USON-10 2.5x1mm_ Pitch 0.5mm")
		(tags "USON-10 2.5x1mm Pitch 0.5mm")
		(property "Reference" "U19"
			(at 0.878749 -1 180)
			(layer "F.SilkS")
			(effects
				(font
					(size 0.7 0.7)
					(thickness 0.15)
				)
				(justify left bottom)
			)
		)
		(property "Value" "TPD4E05U06QDQARQ1"
			(at 0.018 2.499 90)
			(layer "F.Fab")
			(effects
				(font
					(size 0.7 0.7)
					(thickness 0.15)
				)
				(justify left bottom)
			)
		)
		(property "Footprint" "antmicro-footprints:USON-10_2.5x1mm_P0.5mm"
			(at 0 0 90)
			(layer "F.Fab")
			(hide yes)
			(effects
				(font
					(size 1.27 1.27)
					(thickness 0.15)
				)
			)
		)
		(property "Datasheet" "https://www.ti.com/lit/ds/symlink/tpd4e05u06-q1.pdf?HQS=dis-mous-null-mousermode-dsf-pf-null-wwe&ts=1663591265741&ref_url=https%253A%252F%252Fwww.mouser.com%252F"
			(at 0 0 90)
			(layer "F.Fab")
			(hide yes)
			(effects
				(font
					(size 1.27 1.27)
					(thickness 0.15)
				)
			)
		)
		(property "Author" "Antmicro"
			(at 232.728749 -0.371251 0)
			(layer "F.Fab")
			(hide yes)
			(effects
				(font
					(size 1 1)
					(thickness 0.15)
				)
			)
		)
		(property "License" "Apache-2.0"
			(at 232.728749 -0.371251 0)
			(layer "F.Fab")
			(hide yes)
			(effects
				(font
					(size 1 1)
					(thickness 0.15)
				)
			)
		)
		(property "MPN" "TPD4E05U06QDQARQ1"
			(at 232.728749 -0.371251 0)
			(layer "F.Fab")
			(hide yes)
			(effects
				(font
					(size 1 1)
					(thickness 0.15)
				)
			)
		)
		(property "Manufacturer" "Texas Instruments"
			(at 232.728749 -0.371251 0)
			(layer "F.Fab")
			(hide yes)
			(effects
				(font
					(size 1 1)
					(thickness 0.15)
				)
			)
		)
		(sheetname "USB3")
		(sheetfile "usb3.kicad_sch")
		(attr smd)
		(fp_line
			(start 0.498 -1.401)
			(end -0.5 -1.401)
			(stroke
				(width 0.15)
				(type solid)
			)
			(layer "F.SilkS")
		)
		(fp_line
			(start 0.498 1.398)
			(end -0.5 1.398)
			(stroke
				(width 0.15)
				(type solid)
			)
			(layer "F.SilkS")
		)
		(fp_circle
			(center -0.68 -1.27)
			(end -0.63 -1.27)
			(stroke
				(width 0.15)
				(type solid)
			)
			(fill solid)
			(layer "F.SilkS")
		)
		(fp_rect
			(start -0.8 -1.5)
			(end 0.8 1.499)
			(stroke
				(width 0.05)
				(type solid)
			)
			(fill none)
			(layer "F.CrtYd")
		)
		(fp_line
			(start 0.498 -1.25)
			(end -0.25 -1.25)
			(stroke
				(width 0.15)
				(type solid)
			)
			(layer "F.Fab")
		)
		(fp_line
			(start 0.498 -1.25)
			(end 0.498 1.249)
			(stroke
				(width 0.15)
				(type solid)
			)
			(layer "F.Fab")
		)
		(fp_line
			(start -0.25 -1.25)
			(end -0.5 -1)
			(stroke
				(width 0.15)
				(type solid)
			)
			(layer "F.Fab")
		)
		(fp_line
			(start -0.5 -1)
			(end -0.5 1.249)
			(stroke
				(width 0.15)
				(type solid)
			)
			(layer "F.Fab")
		)
		(fp_line
			(start -0.5 1.249)
			(end 0.498 1.249)
			(stroke
				(width 0.15)
				(type solid)
			)
			(layer "F.Fab")
		)
		(fp_text user "Author: Antmicro"
			(at -0.802 5.7 90)
			(layer "F.Fab")
			(hide yes)
			(effects
				(font
					(size 0.7 0.7)
					(thickness 0.15)
				)
				(justify left bottom)
			)
		)
		(fp_text user "${REFERENCE}"
			(at -0.802 4.498 90)
			(layer "F.Fab")
			(hide yes)
			(effects
				(font
					(size 0.7 0.7)
					(thickness 0.15)
				)
				(justify left bottom)
			)
		)
		(fp_text user "License: Apache-2.0"
			(at -0.802 6.9 90)
			(layer "F.Fab")
			(hide yes)
			(effects
				(font
					(size 0.7 0.7)
					(thickness 0.15)
				)
				(justify left bottom)
			)
		)
		(pad "1" smd roundrect
			(at -0.387 -1)
			(size 0.25 0.55)
			(layers "F.Cu" "F.Paste" "F.Mask")
			(roundrect_rratio 0.25)
			(net 369 "/USB3/USBC1_RX2_N")
			(pintype "passive")
		)
		(pad "2" smd roundrect
			(at -0.387 -0.5)
			(size 0.25 0.55)
			(layers "F.Cu" "F.Paste" "F.Mask")
			(roundrect_rratio 0.25)
			(net 390 "/USB3/USBC1_RX2_P")
			(pintype "passive")
		)
		(pad "3" smd roundrect
			(at -0.387 0)
			(size 0.4 0.55)
			(layers "F.Cu" "F.Paste" "F.Mask")
			(roundrect_rratio 0.25)
			(net 1 "GND")
			(pintype "power_in")
		)
		(pad "4" smd roundrect
			(at -0.387 0.498)
			(size 0.25 0.55)
			(layers "F.Cu" "F.Paste" "F.Mask")
			(roundrect_rratio 0.25)
			(net 263 "/USB3/USBC1_CONN_TX2_N")
			(pintype "passive")
		)
		(pad "5" smd roundrect
			(at -0.387 0.998)
			(size 0.25 0.55)
			(layers "F.Cu" "F.Paste" "F.Mask")
			(roundrect_rratio 0.25)
			(net 269 "/USB3/USBC1_CONN_TX2_P")
			(pintype "passive")
		)
		(pad "6" smd roundrect
			(at 0.385 0.998)
			(size 0.25 0.55)
			(layers "F.Cu" "F.Paste" "F.Mask")
			(roundrect_rratio 0.25)
			(net 269 "/USB3/USBC1_CONN_TX2_P")
			(pintype "passive")
		)
		(pad "7" smd roundrect
			(at 0.385 0.498)
			(size 0.25 0.55)
			(layers "F.Cu" "F.Paste" "F.Mask")
			(roundrect_rratio 0.25)
			(net 263 "/USB3/USBC1_CONN_TX2_N")
			(pintype "passive")
		)
		(pad "8" smd roundrect
			(at 0.385 0)
			(size 0.4 0.55)
			(layers "F.Cu" "F.Paste" "F.Mask")
			(roundrect_rratio 0.25)
			(net 1 "GND")
			(pintype "passive")
		)
		(pad "9" smd roundrect
			(at 0.385 -0.5)
			(size 0.25 0.55)
			(layers "F.Cu" "F.Paste" "F.Mask")
			(roundrect_rratio 0.25)
			(net 390 "/USB3/USBC1_RX2_P")
			(pintype "passive")
		)
		(pad "10" smd roundrect
			(at 0.385 -1)
			(size 0.25 0.55)
			(layers "F.Cu" "F.Paste" "F.Mask")
			(roundrect_rratio 0.25)
			(net 369 "/USB3/USBC1_RX2_N")
			(pintype "passive")
		)
	)
)
